===================================================================================================
QUANTA Computer Inc. PCIeSW RELEASE NOTES for F0T-Expander BD (Grand Teton)
===================================================================================================
Project Name       : F0T-Expander BD (Grand Teton)
Platfrom Name      : Grand Teton
PCIeSW Vender      : Broadcom
PCIeSW Device      : PEX89144 -PEX89000 Series
Build Date         : 2023/04/17
SDK Version        : 4.10.1
FW Version         : 4.101.0.0
SBR RC Version     : B0-RC10AP
PEX Version        : B0000703
Secuered           : Secuered
Public Key         : brcm-atlas2-quanta-gt-rsa3072-0-pub.pem
PEX# ILFW Checksum : 0x0876BE66/0x0876B965/0x0876BC67/0x0876B66F
 
===================================================================================================
                             IMPORTANT INSTALLATION NOTES
===================================================================================================
PCIeSW FW Upgrade:
    Using BMC: fw-util swb --update pex# GT_SWB_PEX_*.pldm
    Note: # = 0, 1, 2, 3
===================================================================================================
                             KNOWN ISSUES/WORKAROUNDS
===================================================================================================
- N/A
===================================================================================================
                             FEATURES ADDED/MODIFY 
===================================================================================================
Release for B0000703
- Modify SBR and MFG to limit STN2 to gen3.
- Modify SBR to calibrate LMT.

B0000602
- Modify the SBR register 0xDA8 to 0x00408006 from 0x00008007.

B0000502
- Update fw to BRCM package 4.101.0.0
- Modify the np-mem and p-mem to meet GPU's requirement.

B0050000/B0050001/B0050002/B0050003
- Enable Aladin and Viking in Secure_Mode.
- Update SBR to RC10AP.
- Add PEX fw version in UTP.
- Modify VendorID and ProductID for Meta reqest.

B0040000/B0040001/B0040002/B0040003
- Update fw to BRCM package 4.101.110.0
- Modify securityMfgPage follow RDK setting.

B0030000/B0030001/B0030002/B0030003
- Change to 4.101.109.0 by RDK package from EVAL.
- Add NT2 feature.
- Add I2C_3 MCTP by address 0x50~0x53.
- Change trace buffer size.
- Modify description on show command.
- Modify enumeration timing for ODMB.

B0020000/B0020001/B0020002/B0020003
- Modify enumeration timing for BFT.
- Modify I2C_S address in SBR to 0x60, 0x61, 0x62 and 0x63.
- Update FW vergion to 4.101.106.0

B0010000/B0010001/B0010002/B0010003
- Initial release for B0 Silicon.

===================================================================================================
                             FEATURES REMOVED
===================================================================================================
B0000703
- NA

B0000602
- NA

B0000502
- NA

B0050000/B0050001/B0050002/B0050003
- NA

B0040000/B0040001/B0040002/B0040003
- NA

B0030000/B0030001/B0030002/B0030003
- NA

B0020000/B0020001/B0020002/B0020003
- NA

B0010000/B0010001/B0010002/B0010003
- Initial release for B0 Silicon.
===================================================================================================
                             ISSUES FIXED
===================================================================================================
B0000703
- NA

B0000602
- [416746][F0TG_DVT_8 Retimer][DS1] The E1.S was lost 2 device after AC cycle.

B0000502
- NA

B0050000/B0050001/B0050002/B0050003
- NA

B0040000/B0040001/B0040002/B0040003
- NA

B0030000/B0030001/B0030002/B0030003
- NA

B0020000/B0020001/B0020002/B0020003
- NA

B0010000/B0010001/B0010002/B0010003
- Initial release for B0 Silicon.
[END OF RELEASE NOTES]
